(kicad_pcb
	(version 20260206)
	(generator "pcbnew")
	(generator_version "10.0")
	(general
		(thickness 1.6)
		(legacy_teardrops no)
	)
	(paper "A4")
	(title_block
		(title "04192023_DAF0TMB3IC0_F0TG_MB_C_brd_V02_OCP.brd")
		(comment 1 "Grand Teton / footprint 3955 of 8354 (U25), pads 652-759 of 6102")
	)
	(layers
		(0 "F.Cu" signal "TOP")
		(4 "In1.Cu" signal "GND")
		(6 "In2.Cu" signal "IN1")
		(8 "In3.Cu" signal "GND1")
		(10 "In4.Cu" signal "IN2")
		(12 "In5.Cu" signal "GND2")
		(14 "In6.Cu" signal "IN3")
		(16 "In7.Cu" signal "GND3")
		(18 "In8.Cu" signal "VCC")
		(20 "In9.Cu" signal "VCC1")
		(22 "In10.Cu" signal "GND4")
		(24 "In11.Cu" signal "IN4")
		(26 "In12.Cu" signal "GND5")
		(28 "In13.Cu" signal "IN5")
		(30 "In14.Cu" signal "GND6")
		(32 "In15.Cu" signal "IN6")
		(34 "In16.Cu" signal "GND7")
		(2 "B.Cu" signal "BOTTOM")
		(9 "F.Adhes" user "F.Adhesive")
		(11 "B.Adhes" user "B.Adhesive")
		(13 "F.Paste" user "Package Geometry/Pastemask Top")
		(15 "B.Paste" user "Package Geometry/Pastemask Bottom")
		(5 "F.SilkS" user "Ref Des/Silkscreen Top")
		(7 "B.SilkS" user "Ref Des/Silkscreen Bottom")
		(1 "F.Mask" user "Board Geometry/Soldermask Top")
		(3 "B.Mask" user "Board Geometry/Soldermask Bottom")
		(17 "Dwgs.User" user "User.Drawings")
		(19 "Cmts.User" user "User.Comments")
		(21 "Eco1.User" user "User.Eco1")
		(23 "Eco2.User" user "User.Eco2")
		(25 "Edge.Cuts" user "Board Geometry/Outline")
		(27 "Margin" user)
		(31 "F.CrtYd" user "Package Geometry/Place Bound Top")
		(29 "B.CrtYd" user "Package Geometry/Place Bound Bottom")
		(35 "F.Fab" user "Ref Des/Assembly Top")
		(33 "B.Fab" user "Ref Des/Assembly Bottom")
	)
	(footprint ""
		(layer "F.Cu")
		(at 359.867962 -258.880102 180)
		(property "Reference" "U25"
			(at -45.78477 -62.086744 0)
			(unlocked yes)
			(layer "F.SilkS")
			(effects
				(font
					(size 0.7874 0.5842)
					(thickness 0.1524)
				)
			)
		)
		(property "Value" ""
			(at 0 0 180)
			(layer "F.Fab")
			(effects
				(font
					(size 1.27 1.27)
				)
			)
		)
		(duplicate_pad_numbers_are_jumpers no)
		(pad "AJ14" smd circle
			(at -21.940012 -14.13002 180)
			(size 0.450088 0.450088)
			(layers "F.Cu" "F.Mask" "F.Paste")
			(net "M_H_CPU0_SA_DQ<31>")
		)
		(pad "AJ15" smd circle
			(at -20.999958 -14.13002 180)
			(size 0.450088 0.450088)
			(layers "F.Cu" "F.Mask" "F.Paste")
			(net "GND")
		)
		(pad "AJ16" smd circle
			(at -20.059904 -14.13002 180)
			(size 0.450088 0.450088)
			(layers "F.Cu" "F.Mask" "F.Paste")
			(net "M_J_CPU0_SA_CB<0>")
		)
		(pad "AJ17" smd circle
			(at -19.120104 -14.13002 180)
			(size 0.450088 0.450088)
			(layers "F.Cu" "F.Mask" "F.Paste")
			(net "M_J_CPU0_SA_DQ<31>")
		)
		(pad "AJ18" smd circle
			(at -18.18005 -14.13002 180)
			(size 0.450088 0.450088)
			(layers "F.Cu" "F.Mask" "F.Paste")
			(net "PVDDCR_SOC_P0")
		)
		(pad "AJ19" smd circle
			(at -17.239996 -14.13002 180)
			(size 0.450088 0.450088)
			(layers "F.Cu" "F.Mask" "F.Paste")
			(net "M_I_CPU0_SA_CB<0>")
		)
		(pad "AJ20" smd circle
			(at -16.299942 -14.13002 180)
			(size 0.450088 0.450088)
			(layers "F.Cu" "F.Mask" "F.Paste")
			(net "GND")
		)
		(pad "AJ21" smd circle
			(at -15.359888 -14.13002 180)
			(size 0.450088 0.450088)
			(layers "F.Cu" "F.Mask" "F.Paste")
			(net "M_I_CPU0_SA_DQ<31>")
		)
		(pad "AJ22" smd circle
			(at -14.420088 -14.13002 180)
			(size 0.450088 0.450088)
			(layers "F.Cu" "F.Mask" "F.Paste")
			(net "GND")
		)
		(pad "AJ23" smd circle
			(at -13.480034 -14.13002 180)
			(size 0.450088 0.450088)
			(layers "F.Cu" "F.Mask" "F.Paste")
			(net "P5E_CPU0_G3_RX_DN<1>")
		)
		(pad "AJ24" smd circle
			(at -12.53998 -14.13002 180)
			(size 0.450088 0.450088)
			(layers "F.Cu" "F.Mask" "F.Paste")
			(net "P5E_CPU0_G3_RX_DP<1>")
		)
		(pad "AJ25" smd circle
			(at -11.599926 -14.13002 180)
			(size 0.450088 0.450088)
			(layers "F.Cu" "F.Mask" "F.Paste")
			(net "GND")
		)
		(pad "AJ26" smd circle
			(at -10.659872 -14.13002 180)
			(size 0.450088 0.450088)
			(layers "F.Cu" "F.Mask" "F.Paste")
			(net "P5E_CPU0_G3_RX_DN<4>")
		)
		(pad "AJ27" smd circle
			(at -9.720072 -14.13002 180)
			(size 0.450088 0.450088)
			(layers "F.Cu" "F.Mask" "F.Paste")
			(net "P5E_CPU0_G3_RX_DP<4>")
		)
		(pad "AJ28" smd circle
			(at -8.780018 -14.13002 180)
			(size 0.450088 0.450088)
			(layers "F.Cu" "F.Mask" "F.Paste")
			(net "GND")
		)
		(pad "AJ29" smd circle
			(at -7.839964 -14.13002 180)
			(size 0.450088 0.450088)
			(layers "F.Cu" "F.Mask" "F.Paste")
			(net "P5E_CPU0_G3_RX_DN<7>")
		)
		(pad "AJ30" smd circle
			(at -6.89991 -14.13002 180)
			(size 0.450088 0.450088)
			(layers "F.Cu" "F.Mask" "F.Paste")
			(net "P5E_CPU0_G3_RX_DP<7>")
		)
		(pad "AJ31" smd circle
			(at -5.96011 -14.13002 180)
			(size 0.450088 0.450088)
			(layers "F.Cu" "F.Mask" "F.Paste")
			(net "GND")
		)
		(pad "AJ32" smd circle
			(at -5.020056 -14.13002 180)
			(size 0.450088 0.450088)
			(layers "F.Cu" "F.Mask" "F.Paste")
			(net "P5E_CPU0_G3_RX_DN<10>")
		)
		(pad "AJ33" smd circle
			(at -4.080002 -14.13002 180)
			(size 0.450088 0.450088)
			(layers "F.Cu" "F.Mask" "F.Paste")
			(net "P5E_CPU0_G3_RX_DP<10>")
		)
		(pad "AJ34" smd circle
			(at -3.139948 -14.13002 180)
			(size 0.450088 0.450088)
			(layers "F.Cu" "F.Mask" "F.Paste")
			(net "GND")
		)
		(pad "AJ35" smd circle
			(at -2.199894 -14.13002 180)
			(size 0.450088 0.450088)
			(layers "F.Cu" "F.Mask" "F.Paste")
			(net "GND")
		)
		(pad "AJ36" smd circle
			(at -1.260094 -14.13002 180)
			(size 0.450088 0.450088)
			(layers "F.Cu" "F.Mask" "F.Paste")
			(net "GND")
		)
		(pad "AJ40" smd circle
			(at 1.560068 -14.13002 180)
			(size 0.450088 0.450088)
			(layers "F.Cu" "F.Mask" "F.Paste")
			(net "GND")
		)
		(pad "AJ41" smd circle
			(at 2.500122 -14.13002 180)
			(size 0.450088 0.450088)
			(layers "F.Cu" "F.Mask" "F.Paste")
			(net "GND")
		)
		(pad "AJ42" smd circle
			(at 3.439922 -14.13002 180)
			(size 0.450088 0.450088)
			(layers "F.Cu" "F.Mask" "F.Paste")
			(net "GND")
		)
		(pad "AJ43" smd circle
			(at 4.379976 -14.13002 180)
			(size 0.450088 0.450088)
			(layers "F.Cu" "F.Mask" "F.Paste")
			(net "GMI_CPU0_G1_CPU1_G3_TX_DP<5>")
		)
		(pad "AJ44" smd circle
			(at 5.32003 -14.13002 180)
			(size 0.450088 0.450088)
			(layers "F.Cu" "F.Mask" "F.Paste")
			(net "GMI_CPU0_G1_CPU1_G3_TX_DN<5>")
		)
		(pad "AJ45" smd circle
			(at 6.260084 -14.13002 180)
			(size 0.450088 0.450088)
			(layers "F.Cu" "F.Mask" "F.Paste")
			(net "GND")
		)
		(pad "AJ46" smd circle
			(at 7.199884 -14.13002 180)
			(size 0.450088 0.450088)
			(layers "F.Cu" "F.Mask" "F.Paste")
			(net "GMI_CPU0_G1_CPU1_G3_TX_DP<8>")
		)
		(pad "AJ47" smd circle
			(at 8.139938 -14.13002 180)
			(size 0.450088 0.450088)
			(layers "F.Cu" "F.Mask" "F.Paste")
			(net "GMI_CPU0_G1_CPU1_G3_TX_DN<8>")
		)
		(pad "AJ48" smd circle
			(at 9.079992 -14.13002 180)
			(size 0.450088 0.450088)
			(layers "F.Cu" "F.Mask" "F.Paste")
			(net "GND")
		)
		(pad "AJ49" smd circle
			(at 10.020046 -14.13002 180)
			(size 0.450088 0.450088)
			(layers "F.Cu" "F.Mask" "F.Paste")
			(net "GMI_CPU0_G1_CPU1_G3_TX_DP<11>")
		)
		(pad "AJ50" smd circle
			(at 10.9601 -14.13002 180)
			(size 0.450088 0.450088)
			(layers "F.Cu" "F.Mask" "F.Paste")
			(net "GMI_CPU0_G1_CPU1_G3_TX_DN<11>")
		)
		(pad "AJ51" smd circle
			(at 11.8999 -14.13002 180)
			(size 0.450088 0.450088)
			(layers "F.Cu" "F.Mask" "F.Paste")
			(net "GND")
		)
		(pad "AJ52" smd circle
			(at 12.839954 -14.13002 180)
			(size 0.450088 0.450088)
			(layers "F.Cu" "F.Mask" "F.Paste")
			(net "GMI_CPU0_G1_CPU1_G3_TX_DP<14>")
		)
		(pad "AJ53" smd circle
			(at 13.780008 -14.13002 180)
			(size 0.450088 0.450088)
			(layers "F.Cu" "F.Mask" "F.Paste")
			(net "GMI_CPU0_G1_CPU1_G3_TX_DN<14>")
		)
		(pad "AJ54" smd circle
			(at 14.720062 -14.13002 180)
			(size 0.450088 0.450088)
			(layers "F.Cu" "F.Mask" "F.Paste")
			(net "GND")
		)
		(pad "AJ55" smd circle
			(at 15.660116 -14.13002 180)
			(size 0.450088 0.450088)
			(layers "F.Cu" "F.Mask" "F.Paste")
			(net "M_C_CPU0_SA_DQ<31>")
		)
		(pad "AJ56" smd circle
			(at 16.599916 -14.13002 180)
			(size 0.450088 0.450088)
			(layers "F.Cu" "F.Mask" "F.Paste")
			(net "GND")
		)
		(pad "AJ57" smd circle
			(at 17.53997 -14.13002 180)
			(size 0.450088 0.450088)
			(layers "F.Cu" "F.Mask" "F.Paste")
			(net "M_C_CPU0_SA_CB<0>")
		)
		(pad "AJ58" smd circle
			(at 18.480024 -14.13002 180)
			(size 0.450088 0.450088)
			(layers "F.Cu" "F.Mask" "F.Paste")
			(net "PVDDIO_P0")
		)
		(pad "AJ59" smd circle
			(at 19.420078 -14.13002 180)
			(size 0.450088 0.450088)
			(layers "F.Cu" "F.Mask" "F.Paste")
			(net "M_D_CPU0_SA_DQ<31>")
		)
		(pad "AJ60" smd circle
			(at 20.359878 -14.13002 180)
			(size 0.450088 0.450088)
			(layers "F.Cu" "F.Mask" "F.Paste")
			(net "M_D_CPU0_SA_CB<0>")
		)
		(pad "AJ61" smd circle
			(at 21.299932 -14.13002 180)
			(size 0.450088 0.450088)
			(layers "F.Cu" "F.Mask" "F.Paste")
			(net "GND")
		)
		(pad "AJ62" smd circle
			(at 22.239986 -14.13002 180)
			(size 0.450088 0.450088)
			(layers "F.Cu" "F.Mask" "F.Paste")
			(net "M_B_CPU0_SA_DQ<31>")
		)
		(pad "AJ63" smd circle
			(at 23.18004 -14.13002 180)
			(size 0.450088 0.450088)
			(layers "F.Cu" "F.Mask" "F.Paste")
			(net "GND")
		)
		(pad "AJ64" smd circle
			(at 24.120094 -14.13002 180)
			(size 0.450088 0.450088)
			(layers "F.Cu" "F.Mask" "F.Paste")
			(net "M_B_CPU0_SA_CB<0>")
		)
		(pad "AJ65" smd circle
			(at 25.059894 -14.13002 180)
			(size 0.450088 0.450088)
			(layers "F.Cu" "F.Mask" "F.Paste")
			(net "PVDDIO_P0")
		)
		(pad "AJ66" smd circle
			(at 25.999948 -14.13002 180)
			(size 0.450088 0.450088)
			(layers "F.Cu" "F.Mask" "F.Paste")
			(net "M_F_CPU0_SA_DQ<31>")
		)
		(pad "AJ67" smd circle
			(at 26.940002 -14.13002 180)
			(size 0.450088 0.450088)
			(layers "F.Cu" "F.Mask" "F.Paste")
			(net "M_F_CPU0_SA_CB<0>")
		)
		(pad "AJ68" smd circle
			(at 27.880056 -14.13002 180)
			(size 0.450088 0.450088)
			(layers "F.Cu" "F.Mask" "F.Paste")
			(net "GND")
		)
		(pad "AJ69" smd circle
			(at 28.82011 -14.13002 180)
			(size 0.450088 0.450088)
			(layers "F.Cu" "F.Mask" "F.Paste")
			(net "M_E_CPU0_SA_DQ<31>")
		)
		(pad "AJ70" smd circle
			(at 29.75991 -14.13002 180)
			(size 0.450088 0.450088)
			(layers "F.Cu" "F.Mask" "F.Paste")
			(net "GND")
		)
		(pad "AJ71" smd circle
			(at 30.699964 -14.13002 180)
			(size 0.450088 0.450088)
			(layers "F.Cu" "F.Mask" "F.Paste")
			(net "M_E_CPU0_SA_CB<0>")
		)
		(pad "AJ72" smd circle
			(at 31.640018 -14.13002 180)
			(size 0.450088 0.450088)
			(layers "F.Cu" "F.Mask" "F.Paste")
			(net "PVDDIO_P0")
		)
		(pad "AJ73" smd circle
			(at 32.580072 -14.13002 180)
			(size 0.450088 0.450088)
			(layers "F.Cu" "F.Mask" "F.Paste")
			(net "M_A_CPU0_SA_DQ<31>")
		)
		(pad "AJ74" smd circle
			(at 33.519872 -14.13002 180)
			(size 0.450088 0.450088)
			(layers "F.Cu" "F.Mask" "F.Paste")
			(net "M_A_CPU0_SA_CB<0>")
		)
		(pad "AJ75" smd circle
			(at 34.459926 -14.13002 180)
			(size 0.450088 0.450088)
			(layers "F.Cu" "F.Mask" "F.Paste")
			(net "GND")
		)
		(pad "AK2" smd circle
			(at -33.690052 -13.320014 180)
			(size 0.450088 0.450088)
			(layers "F.Cu" "F.Mask" "F.Paste")
			(net "M_G_CPU0_SA_CB<2>")
		)
		(pad "AK3" smd circle
			(at -32.749998 -13.320014 180)
			(size 0.450088 0.450088)
			(layers "F.Cu" "F.Mask" "F.Paste")
			(net "GND")
		)
		(pad "AK4" smd circle
			(at -31.809944 -13.320014 180)
			(size 0.450088 0.450088)
			(layers "F.Cu" "F.Mask" "F.Paste")
			(net "M_G_CPU0_SA_CB<1>")
		)
		(pad "AK5" smd circle
			(at -30.86989 -13.320014 180)
			(size 0.450088 0.450088)
			(layers "F.Cu" "F.Mask" "F.Paste")
			(net "GND")
		)
		(pad "AK6" smd circle
			(at -29.93009 -13.320014 180)
			(size 0.450088 0.450088)
			(layers "F.Cu" "F.Mask" "F.Paste")
			(net "M_K_CPU0_SA_CB<2>")
		)
		(pad "AK7" smd circle
			(at -28.990036 -13.320014 180)
			(size 0.450088 0.450088)
			(layers "F.Cu" "F.Mask" "F.Paste")
			(net "M_K_CPU0_SA_CB<1>")
		)
		(pad "AK8" smd circle
			(at -28.049982 -13.320014 180)
			(size 0.450088 0.450088)
			(layers "F.Cu" "F.Mask" "F.Paste")
			(net "GND")
		)
		(pad "AK9" smd circle
			(at -27.109928 -13.320014 180)
			(size 0.450088 0.450088)
			(layers "F.Cu" "F.Mask" "F.Paste")
			(net "M_L_CPU0_SA_CB<2>")
		)
		(pad "AK10" smd circle
			(at -26.170128 -13.320014 180)
			(size 0.450088 0.450088)
			(layers "F.Cu" "F.Mask" "F.Paste")
			(net "GND")
		)
		(pad "AK11" smd circle
			(at -25.230074 -13.320014 180)
			(size 0.450088 0.450088)
			(layers "F.Cu" "F.Mask" "F.Paste")
			(net "M_L_CPU0_SA_CB<1>")
		)
		(pad "AK12" smd circle
			(at -24.29002 -13.320014 180)
			(size 0.450088 0.450088)
			(layers "F.Cu" "F.Mask" "F.Paste")
			(net "GND")
		)
		(pad "AK13" smd circle
			(at -23.349966 -13.320014 180)
			(size 0.450088 0.450088)
			(layers "F.Cu" "F.Mask" "F.Paste")
			(net "M_H_CPU0_SA_CB<2>")
		)
		(pad "AK14" smd circle
			(at -22.409912 -13.320014 180)
			(size 0.450088 0.450088)
			(layers "F.Cu" "F.Mask" "F.Paste")
			(net "M_H_CPU0_SA_CB<1>")
		)
		(pad "AK15" smd circle
			(at -21.470112 -13.320014 180)
			(size 0.450088 0.450088)
			(layers "F.Cu" "F.Mask" "F.Paste")
			(net "GND")
		)
		(pad "AK16" smd circle
			(at -20.530058 -13.320014 180)
			(size 0.450088 0.450088)
			(layers "F.Cu" "F.Mask" "F.Paste")
			(net "M_J_CPU0_SA_CB<2>")
		)
		(pad "AK17" smd circle
			(at -19.590004 -13.320014 180)
			(size 0.450088 0.450088)
			(layers "F.Cu" "F.Mask" "F.Paste")
			(net "GND")
		)
		(pad "AK18" smd circle
			(at -18.64995 -13.320014 180)
			(size 0.450088 0.450088)
			(layers "F.Cu" "F.Mask" "F.Paste")
			(net "M_J_CPU0_SA_CB<1>")
		)
		(pad "AK19" smd circle
			(at -17.709896 -13.320014 180)
			(size 0.450088 0.450088)
			(layers "F.Cu" "F.Mask" "F.Paste")
			(net "GND")
		)
		(pad "AK20" smd circle
			(at -16.770096 -13.320014 180)
			(size 0.450088 0.450088)
			(layers "F.Cu" "F.Mask" "F.Paste")
			(net "M_I_CPU0_SA_CB<2>")
		)
		(pad "AK21" smd circle
			(at -15.830042 -13.320014 180)
			(size 0.450088 0.450088)
			(layers "F.Cu" "F.Mask" "F.Paste")
			(net "M_I_CPU0_SA_CB<1>")
		)
		(pad "AK22" smd circle
			(at -14.889988 -13.320014 180)
			(size 0.450088 0.450088)
			(layers "F.Cu" "F.Mask" "F.Paste")
			(net "GND")
		)
		(pad "AK23" smd circle
			(at -13.949934 -13.320014 180)
			(size 0.450088 0.450088)
			(layers "F.Cu" "F.Mask" "F.Paste")
			(net "PVDDCR_CPU0_P0")
		)
		(pad "AK24" smd circle
			(at -13.00988 -13.320014 180)
			(size 0.450088 0.450088)
			(layers "F.Cu" "F.Mask" "F.Paste")
			(net "PVDDCR_CPU0_P0")
		)
		(pad "AK25" smd circle
			(at -12.07008 -13.320014 180)
			(size 0.450088 0.450088)
			(layers "F.Cu" "F.Mask" "F.Paste")
			(net "GND")
		)
		(pad "AK26" smd circle
			(at -11.130026 -13.320014 180)
			(size 0.450088 0.450088)
			(layers "F.Cu" "F.Mask" "F.Paste")
			(net "PVDDCR_CPU0_P0")
		)
		(pad "AK27" smd circle
			(at -10.189972 -13.320014 180)
			(size 0.450088 0.450088)
			(layers "F.Cu" "F.Mask" "F.Paste")
			(net "PVDDCR_CPU0_P0")
		)
		(pad "AK28" smd circle
			(at -9.249918 -13.320014 180)
			(size 0.450088 0.450088)
			(layers "F.Cu" "F.Mask" "F.Paste")
			(net "GND")
		)
		(pad "AK29" smd circle
			(at -8.310118 -13.320014 180)
			(size 0.450088 0.450088)
			(layers "F.Cu" "F.Mask" "F.Paste")
			(net "PVDDCR_CPU0_P0")
		)
		(pad "AK30" smd circle
			(at -7.370064 -13.320014 180)
			(size 0.450088 0.450088)
			(layers "F.Cu" "F.Mask" "F.Paste")
			(net "PVDDCR_CPU0_P0")
		)
		(pad "AK31" smd circle
			(at -6.43001 -13.320014 180)
			(size 0.450088 0.450088)
			(layers "F.Cu" "F.Mask" "F.Paste")
			(net "GND")
		)
		(pad "AK32" smd circle
			(at -5.489956 -13.320014 180)
			(size 0.450088 0.450088)
			(layers "F.Cu" "F.Mask" "F.Paste")
			(net "PVDDCR_CPU0_P0")
		)
		(pad "AK33" smd circle
			(at -4.549902 -13.320014 180)
			(size 0.450088 0.450088)
			(layers "F.Cu" "F.Mask" "F.Paste")
			(net "PVDDCR_CPU0_P0")
		)
		(pad "AK34" smd circle
			(at -3.610102 -13.320014 180)
			(size 0.450088 0.450088)
			(layers "F.Cu" "F.Mask" "F.Paste")
			(net "GND")
		)
		(pad "AK35" smd circle
			(at -2.670048 -13.320014 180)
			(size 0.450088 0.450088)
			(layers "F.Cu" "F.Mask" "F.Paste")
			(net "P5E_CPU0_G3_RX_DN<12>")
		)
		(pad "AK36" smd circle
			(at -1.729994 -13.320014 180)
			(size 0.450088 0.450088)
			(layers "F.Cu" "F.Mask" "F.Paste")
			(net "P5E_CPU0_G3_RX_DP<12>")
		)
		(pad "AK37" smd circle
			(at -0.78994 -13.320014 180)
			(size 0.450088 0.450088)
			(layers "F.Cu" "F.Mask" "F.Paste")
			(net "GND")
		)
		(pad "AK39" smd circle
			(at 1.089914 -13.320014 180)
			(size 0.450088 0.450088)
			(layers "F.Cu" "F.Mask" "F.Paste")
			(net "GND")
		)
		(pad "AK40" smd circle
			(at 2.029968 -13.320014 180)
			(size 0.450088 0.450088)
			(layers "F.Cu" "F.Mask" "F.Paste")
			(net "GMI_CPU0_G1_CPU1_G3_TX_DP<3>")
		)
		(pad "AK41" smd circle
			(at 2.970022 -13.320014 180)
			(size 0.450088 0.450088)
			(layers "F.Cu" "F.Mask" "F.Paste")
			(net "GMI_CPU0_G1_CPU1_G3_TX_DN<3>")
		)
		(pad "AK42" smd circle
			(at 3.910076 -13.320014 180)
			(size 0.450088 0.450088)
			(layers "F.Cu" "F.Mask" "F.Paste")
			(net "GND")
		)
		(pad "AK43" smd circle
			(at 4.849876 -13.320014 180)
			(size 0.450088 0.450088)
			(layers "F.Cu" "F.Mask" "F.Paste")
			(net "PVDDCR_CPU0_P0")
		)
		(pad "AK44" smd circle
			(at 5.78993 -13.320014 180)
			(size 0.450088 0.450088)
			(layers "F.Cu" "F.Mask" "F.Paste")
			(net "PVDDCR_CPU0_P0")
		)
		(pad "AK45" smd circle
			(at 6.729984 -13.320014 180)
			(size 0.450088 0.450088)
			(layers "F.Cu" "F.Mask" "F.Paste")
			(net "GND")
		)
		(pad "AK46" smd circle
			(at 7.670038 -13.320014 180)
			(size 0.450088 0.450088)
			(layers "F.Cu" "F.Mask" "F.Paste")
			(net "PVDDCR_CPU0_P0")
		)
		(pad "AK47" smd circle
			(at 8.610092 -13.320014 180)
			(size 0.450088 0.450088)
			(layers "F.Cu" "F.Mask" "F.Paste")
			(net "PVDDCR_CPU0_P0")
		)
		(pad "AK48" smd circle
			(at 9.549892 -13.320014 180)
			(size 0.450088 0.450088)
			(layers "F.Cu" "F.Mask" "F.Paste")
			(net "GND")
		)
		(pad "AK49" smd circle
			(at 10.489946 -13.320014 180)
			(size 0.450088 0.450088)
			(layers "F.Cu" "F.Mask" "F.Paste")
			(net "PVDDCR_CPU0_P0")
		)
		(pad "AK50" smd circle
			(at 11.43 -13.320014 180)
			(size 0.450088 0.450088)
			(layers "F.Cu" "F.Mask" "F.Paste")
			(net "PVDDCR_CPU0_P0")
		)
		(pad "AK51" smd circle
			(at 12.370054 -13.320014 180)
			(size 0.450088 0.450088)
			(layers "F.Cu" "F.Mask" "F.Paste")
			(net "GND")
		)
	)
)
